(kicad_pcb
	(version 20260206)
	(generator "pcbnew")
	(generator_version "10.0")
	(general
		(thickness 1.6)
		(legacy_teardrops no)
	)
	(paper "A4")
	(title_block
		(title "Bryce Canyon_IOM_IOC_16318-2_OCP.brd")
		(comment 1 "Bryce Canyon / footprints 1162-1170 of 1605")
	)
	(layers
		(0 "F.Cu" signal "TOP")
		(4 "In1.Cu" signal "L2GND")
		(6 "In2.Cu" signal "L3")
		(8 "In3.Cu" signal "L4VCC")
		(10 "In4.Cu" signal "L5VCC")
		(12 "In5.Cu" signal "L6")
		(14 "In6.Cu" signal "L7GND")
		(2 "B.Cu" signal "BOTTOM")
		(9 "F.Adhes" user "F.Adhesive")
		(11 "B.Adhes" user "B.Adhesive")
		(13 "F.Paste" user "Package Geometry/Pastemask Top")
		(15 "B.Paste" user "Package Geometry/Pastemask Bottom")
		(5 "F.SilkS" user "Ref Des/Silkscreen Top")
		(7 "B.SilkS" user "Ref Des/Silkscreen Bottom")
		(1 "F.Mask" user "Board Geometry/Soldermask Top")
		(3 "B.Mask" user "Board Geometry/Soldermask Bottom")
		(17 "Dwgs.User" user "User.Drawings")
		(19 "Cmts.User" user "User.Comments")
		(21 "Eco1.User" user "User.Eco1")
		(23 "Eco2.User" user "User.Eco2")
		(25 "Edge.Cuts" user "Board Geometry/Outline")
		(27 "Margin" user)
		(31 "F.CrtYd" user "Package Geometry/Place Bound Top")
		(29 "B.CrtYd" user "Package Geometry/Place Bound Bottom")
		(35 "F.Fab" user "Ref Des/Assembly Top")
		(33 "B.Fab" user "Ref Des/Assembly Bottom")
	)
	(footprint ""
		(layer "B.Cu")
		(at 184.115202 -68.250308 90)
		(property "Reference" "C473"
			(at 0 0 90)
			(layer "B.SilkS")
			(hide yes)
			(effects
				(font
					(size 1.27 1.27)
				)
				(justify mirror)
			)
		)
		(property "Value" "SC1KP50V2KX-1GP"
			(at -1.1811 -2.7051 90)
			(unlocked yes)
			(layer "B.Fab")
			(hide yes)
			(effects
				(font
					(size 1.016 1.016)
					(thickness 0.1524)
				)
				(justify mirror)
			)
		)
		(property "Device Type" "C402H22"
			(at -1.1811 -4.2291 90)
			(unlocked yes)
			(layer "B.Fab")
			(hide yes)
			(effects
				(font
					(size 1.016 1.016)
					(thickness 0.1524)
				)
				(justify mirror)
			)
		)
		(duplicate_pad_numbers_are_jumpers no)
		(fp_rect
			(start 0.4318 0.9525)
			(end -0.4318 -0.9525)
			(stroke
				(width 0)
				(type default)
			)
			(fill no)
			(layer "B.CrtYd")
		)
		(fp_rect
			(start 0.4318 0.9525)
			(end -0.4318 -0.9525)
			(stroke
				(width 0)
				(type default)
			)
			(fill no)
			(layer "B.Fab")
		)
		(pad "1" smd custom
			(at 0 -0.4445 270)
			(size 0.1524 0.1524)
			(layers "B.Cu" "B.Mask" "B.Paste")
			(net "P1V8")
			(options
				(clearance outline)
				(anchor circle)
			)
			(primitives
				(gr_poly
					(pts
						(arc
							(start 0.3048 0.2032)
							(mid 0.275042 0.275042)
							(end 0.2032 0.3048)
						)
						(arc
							(start -0.2032 0.3048)
							(mid -0.275042 0.275042)
							(end -0.3048 0.2032)
						)
						(arc
							(start -0.3048 -0.2032)
							(mid -0.275042 -0.275042)
							(end -0.2032 -0.3048)
						)
						(arc
							(start 0.2032 -0.3048)
							(mid 0.275042 -0.275042)
							(end 0.3048 -0.2032)
						)
					)
					(width 0)
					(fill yes)
				)
			)
		)
		(pad "2" smd custom
			(at 0 0.4445 270)
			(size 0.1524 0.1524)
			(layers "B.Cu" "B.Mask" "B.Paste")
			(net "GND")
			(options
				(clearance outline)
				(anchor circle)
			)
			(primitives
				(gr_poly
					(pts
						(arc
							(start 0.3048 0.2032)
							(mid 0.275042 0.275042)
							(end 0.2032 0.3048)
						)
						(arc
							(start -0.2032 0.3048)
							(mid -0.275042 0.275042)
							(end -0.3048 0.2032)
						)
						(arc
							(start -0.3048 -0.2032)
							(mid -0.275042 -0.275042)
							(end -0.2032 -0.3048)
						)
						(arc
							(start 0.2032 -0.3048)
							(mid 0.275042 -0.275042)
							(end 0.3048 -0.2032)
						)
					)
					(width 0)
					(fill yes)
				)
			)
		)
	)
	(footprint ""
		(layer "B.Cu")
		(at 184.6326 -69.9008 90)
		(property "Reference" "C467"
			(at 0 0 90)
			(layer "B.SilkS")
			(hide yes)
			(effects
				(font
					(size 1.27 1.27)
				)
				(justify mirror)
			)
		)
		(property "Value" "SCD1U16V2KX-3GP"
			(at -1.1811 -2.7051 90)
			(unlocked yes)
			(layer "B.Fab")
			(hide yes)
			(effects
				(font
					(size 1.016 1.016)
					(thickness 0.1524)
				)
				(justify mirror)
			)
		)
		(property "Device Type" "C402H22"
			(at -1.1811 -4.2291 90)
			(unlocked yes)
			(layer "B.Fab")
			(hide yes)
			(effects
				(font
					(size 1.016 1.016)
					(thickness 0.1524)
				)
				(justify mirror)
			)
		)
		(duplicate_pad_numbers_are_jumpers no)
		(fp_rect
			(start 0.4318 0.9525)
			(end -0.4318 -0.9525)
			(stroke
				(width 0)
				(type default)
			)
			(fill no)
			(layer "B.CrtYd")
		)
		(fp_rect
			(start 0.4318 0.9525)
			(end -0.4318 -0.9525)
			(stroke
				(width 0)
				(type default)
			)
			(fill no)
			(layer "B.Fab")
		)
		(pad "1" smd custom
			(at 0 -0.4445 270)
			(size 0.1524 0.1524)
			(layers "B.Cu" "B.Mask" "B.Paste")
			(net "P1V8")
			(options
				(clearance outline)
				(anchor circle)
			)
			(primitives
				(gr_poly
					(pts
						(arc
							(start 0.3048 0.2032)
							(mid 0.275042 0.275042)
							(end 0.2032 0.3048)
						)
						(arc
							(start -0.2032 0.3048)
							(mid -0.275042 0.275042)
							(end -0.3048 0.2032)
						)
						(arc
							(start -0.3048 -0.2032)
							(mid -0.275042 -0.275042)
							(end -0.2032 -0.3048)
						)
						(arc
							(start 0.2032 -0.3048)
							(mid 0.275042 -0.275042)
							(end 0.3048 -0.2032)
						)
					)
					(width 0)
					(fill yes)
				)
			)
		)
		(pad "2" smd custom
			(at 0 0.4445 270)
			(size 0.1524 0.1524)
			(layers "B.Cu" "B.Mask" "B.Paste")
			(net "GND")
			(options
				(clearance outline)
				(anchor circle)
			)
			(primitives
				(gr_poly
					(pts
						(arc
							(start 0.3048 0.2032)
							(mid 0.275042 0.275042)
							(end 0.2032 0.3048)
						)
						(arc
							(start -0.2032 0.3048)
							(mid -0.275042 0.275042)
							(end -0.3048 0.2032)
						)
						(arc
							(start -0.3048 -0.2032)
							(mid -0.275042 -0.275042)
							(end -0.2032 -0.3048)
						)
						(arc
							(start 0.2032 -0.3048)
							(mid 0.275042 -0.275042)
							(end 0.3048 -0.2032)
						)
					)
					(width 0)
					(fill yes)
				)
			)
		)
	)
	(footprint ""
		(layer "B.Cu")
		(at 45.5168 -133.7818)
		(property "Reference" "R184"
			(at 0 0 0)
			(layer "B.SilkS")
			(hide yes)
			(effects
				(font
					(size 1.27 1.27)
				)
				(justify mirror)
			)
		)
		(property "Value" "2K2R2F-GP"
			(at -0.064008 -3.993896 0)
			(unlocked yes)
			(layer "B.Fab")
			(hide yes)
			(effects
				(font
					(size 1.016 1.016)
					(thickness 0.1524)
				)
				(justify mirror)
			)
		)
		(property "Device Type" "R402H16"
			(at -0.064008 -5.517896 0)
			(unlocked yes)
			(layer "B.Fab")
			(hide yes)
			(effects
				(font
					(size 1.016 1.016)
					(thickness 0.1524)
				)
				(justify mirror)
			)
		)
		(duplicate_pad_numbers_are_jumpers no)
		(fp_line
			(start -0.508 -0.9398)
			(end 0.508 -0.9398)
			(stroke
				(width 0.1524)
				(type default)
			)
			(layer "B.SilkS")
		)
		(fp_line
			(start 0.508 -0.9398)
			(end 0.508 0.9398)
			(stroke
				(width 0.1524)
				(type default)
			)
			(layer "B.SilkS")
		)
		(fp_rect
			(start 0.508 0.9398)
			(end -0.508 -0.9398)
			(stroke
				(width 0)
				(type default)
			)
			(fill no)
			(layer "B.CrtYd")
		)
		(fp_rect
			(start 0.508 0.9398)
			(end -0.508 -0.9398)
			(stroke
				(width 0)
				(type default)
			)
			(fill no)
			(layer "B.Fab")
		)
		(pad "1" smd custom
			(at 0 -0.4445 180)
			(size 0.1397 0.1397)
			(layers "B.Cu" "B.Mask" "B.Paste")
			(net "I2C_IOM_SDA")
			(options
				(clearance outline)
				(anchor circle)
			)
			(primitives
				(gr_poly
					(pts
						(arc
							(start -0.1778 0.2794)
							(mid -0.249642 0.249642)
							(end -0.2794 0.1778)
						)
						(arc
							(start -0.2794 -0.1778)
							(mid -0.249642 -0.249642)
							(end -0.1778 -0.2794)
						)
						(arc
							(start 0.1778 -0.2794)
							(mid 0.249642 -0.249642)
							(end 0.2794 -0.1778)
						)
						(arc
							(start 0.2794 0.1778)
							(mid 0.249642 0.249642)
							(end 0.1778 0.2794)
						)
					)
					(width 0)
					(fill yes)
				)
			)
		)
		(pad "2" smd custom
			(at 0 0.4445 180)
			(size 0.1397 0.1397)
			(layers "B.Cu" "B.Mask" "B.Paste")
			(net "P3V3_STBY")
			(options
				(clearance outline)
				(anchor circle)
			)
			(primitives
				(gr_poly
					(pts
						(arc
							(start -0.1778 0.2794)
							(mid -0.249642 0.249642)
							(end -0.2794 0.1778)
						)
						(arc
							(start -0.2794 -0.1778)
							(mid -0.249642 -0.249642)
							(end -0.1778 -0.2794)
						)
						(arc
							(start 0.1778 -0.2794)
							(mid 0.249642 -0.249642)
							(end 0.2794 -0.1778)
						)
						(arc
							(start 0.2794 0.1778)
							(mid 0.249642 0.249642)
							(end 0.1778 0.2794)
						)
					)
					(width 0)
					(fill yes)
				)
			)
		)
	)
	(footprint ""
		(layer "B.Cu")
		(at 43.2308 -153.3144 -90)
		(property "Reference" "TP66"
			(at 0 0 90)
			(layer "B.SilkS")
			(hide yes)
			(effects
				(font
					(size 1.27 1.27)
				)
				(justify mirror)
			)
		)
		(property "Value" "TPAD28-2-GP"
			(at 0.0127 -1.6637 270)
			(unlocked yes)
			(layer "B.Fab")
			(hide yes)
			(effects
				(font
					(size 1.016 1.016)
					(thickness 0.1524)
				)
				(justify mirror)
			)
		)
		(property "Device Type" "TPAD28"
			(at 0.0127 -3.1877 270)
			(unlocked yes)
			(layer "B.Fab")
			(hide yes)
			(effects
				(font
					(size 1.016 1.016)
					(thickness 0.1524)
				)
				(justify mirror)
			)
		)
		(duplicate_pad_numbers_are_jumpers no)
		(fp_poly
			(pts
				(arc
					(start 0 -0.3556)
					(mid 0 0.3556)
					(end 0 -0.3556)
				)
			)
			(stroke
				(width 0)
				(type default)
			)
			(fill no)
			(layer "B.CrtYd")
		)
		(fp_poly
			(pts
				(arc
					(start 0 -0.6096)
					(mid 0 0.6096)
					(end 0 -0.6096)
				)
			)
			(stroke
				(width 0)
				(type default)
			)
			(fill no)
			(layer "B.Fab")
		)
		(pad "1" smd circle
			(at 0 0 90)
			(size 0.7112 0.7112)
			(layers "B.Cu" "B.Mask" "B.Paste")
			(net "TP_BMC_GPION7")
		)
	)
	(footprint ""
		(layer "B.Cu")
		(at 190.3984 -120.6246 -90)
		(property "Reference" "C283"
			(at 0 0 90)
			(layer "B.SilkS")
			(hide yes)
			(effects
				(font
					(size 1.27 1.27)
				)
				(justify mirror)
			)
		)
		(property "Value" "SC22U6D3V6KX-2-GP"
			(at 0.0762 -5.1308 270)
			(unlocked yes)
			(layer "B.Fab")
			(hide yes)
			(effects
				(font
					(size 1.016 1.016)
					(thickness 0.1524)
				)
				(justify mirror)
			)
		)
		(property "Device Type" "C1206H71"
			(at 0.127 -6.6548 270)
			(unlocked yes)
			(layer "B.Fab")
			(hide yes)
			(effects
				(font
					(size 1.016 1.016)
					(thickness 0.1524)
				)
				(justify mirror)
			)
		)
		(duplicate_pad_numbers_are_jumpers no)
		(fp_line
			(start -1.016 2.2352)
			(end 1.016 2.2352)
			(stroke
				(width 0.1524)
				(type default)
			)
			(layer "B.SilkS")
		)
		(fp_line
			(start 1.016 2.2352)
			(end 1.016 0.8382)
			(stroke
				(width 0.1524)
				(type default)
			)
			(layer "B.SilkS")
		)
		(fp_line
			(start -1.016 0.8382)
			(end -1.016 2.2352)
			(stroke
				(width 0.1524)
				(type default)
			)
			(layer "B.SilkS")
		)
		(fp_line
			(start 1.016 -0.8382)
			(end 1.016 -2.2352)
			(stroke
				(width 0.1524)
				(type default)
			)
			(layer "B.SilkS")
		)
		(fp_line
			(start -1.016 -2.2352)
			(end -1.016 -0.8382)
			(stroke
				(width 0.1524)
				(type default)
			)
			(layer "B.SilkS")
		)
		(fp_line
			(start 1.016 -2.2352)
			(end -1.016 -2.2352)
			(stroke
				(width 0.1524)
				(type default)
			)
			(layer "B.SilkS")
		)
		(fp_rect
			(start 1.0922 2.3114)
			(end -1.0922 -2.3114)
			(stroke
				(width 0)
				(type default)
			)
			(fill no)
			(layer "B.CrtYd")
		)
		(fp_poly
			(pts
				(xy -1.0922 -2.3114) (xy -1.0922 2.3114) (xy 1.0922 2.3114) (xy 1.0922 -2.3114)
			)
			(stroke
				(width 0)
				(type default)
			)
			(fill no)
			(layer "B.Fab")
		)
		(pad "1" smd rect
			(at 0 -1.397 90)
			(size 1.651 1.27)
			(layers "B.Cu" "B.Mask" "B.Paste")
			(net "VT235_VDDL")
		)
		(pad "2" smd rect
			(at 0 1.397 90)
			(size 1.651 1.27)
			(layers "B.Cu" "B.Mask" "B.Paste")
			(net "GND")
		)
	)
	(footprint ""
		(layer "B.Cu")
		(at 205.7654 -56.9468 180)
		(property "Reference" "R595"
			(at 0 0 0)
			(layer "B.SilkS")
			(hide yes)
			(effects
				(font
					(size 1.27 1.27)
				)
				(justify mirror)
			)
		)
		(property "Value" "2K2R2F-GP"
			(at -0.064008 -3.993896 180)
			(unlocked yes)
			(layer "B.Fab")
			(hide yes)
			(effects
				(font
					(size 1.016 1.016)
					(thickness 0.1524)
				)
				(justify mirror)
			)
		)
		(property "Device Type" "R402H16"
			(at -0.064008 -5.517896 180)
			(unlocked yes)
			(layer "B.Fab")
			(hide yes)
			(effects
				(font
					(size 1.016 1.016)
					(thickness 0.1524)
				)
				(justify mirror)
			)
		)
		(duplicate_pad_numbers_are_jumpers no)
		(fp_line
			(start 0.508 -0.9398)
			(end 0.508 0.9398)
			(stroke
				(width 0.1524)
				(type default)
			)
			(layer "B.SilkS")
		)
		(fp_line
			(start -0.508 -0.9398)
			(end 0.508 -0.9398)
			(stroke
				(width 0.1524)
				(type default)
			)
			(layer "B.SilkS")
		)
		(fp_rect
			(start 0.508 0.9398)
			(end -0.508 -0.9398)
			(stroke
				(width 0)
				(type default)
			)
			(fill no)
			(layer "B.CrtYd")
		)
		(fp_rect
			(start 0.508 0.9398)
			(end -0.508 -0.9398)
			(stroke
				(width 0)
				(type default)
			)
			(fill no)
			(layer "B.Fab")
		)
		(pad "1" smd custom
			(at 0 -0.4445)
			(size 0.1397 0.1397)
			(layers "B.Cu" "B.Mask" "B.Paste")
			(net "P1V8")
			(options
				(clearance outline)
				(anchor circle)
			)
			(primitives
				(gr_poly
					(pts
						(arc
							(start -0.1778 0.2794)
							(mid -0.249642 0.249642)
							(end -0.2794 0.1778)
						)
						(arc
							(start -0.2794 -0.1778)
							(mid -0.249642 -0.249642)
							(end -0.1778 -0.2794)
						)
						(arc
							(start 0.1778 -0.2794)
							(mid 0.249642 -0.249642)
							(end 0.2794 -0.1778)
						)
						(arc
							(start 0.2794 0.1778)
							(mid 0.249642 0.249642)
							(end 0.1778 0.2794)
						)
					)
					(width 0)
					(fill yes)
				)
			)
		)
		(pad "2" smd custom
			(at 0 0.4445)
			(size 0.1397 0.1397)
			(layers "B.Cu" "B.Mask" "B.Paste")
			(net "SIO_LOAD_1")
			(options
				(clearance outline)
				(anchor circle)
			)
			(primitives
				(gr_poly
					(pts
						(arc
							(start -0.1778 0.2794)
							(mid -0.249642 0.249642)
							(end -0.2794 0.1778)
						)
						(arc
							(start -0.2794 -0.1778)
							(mid -0.249642 -0.249642)
							(end -0.1778 -0.2794)
						)
						(arc
							(start 0.1778 -0.2794)
							(mid 0.249642 -0.249642)
							(end 0.2794 -0.1778)
						)
						(arc
							(start 0.2794 0.1778)
							(mid 0.249642 0.249642)
							(end 0.1778 0.2794)
						)
					)
					(width 0)
					(fill yes)
				)
			)
		)
	)
	(footprint ""
		(layer "B.Cu")
		(at 121.397522 -9.64311 180)
		(property "Reference" "CA1"
			(at 0 0 0)
			(layer "B.SilkS")
			(hide yes)
			(effects
				(font
					(size 1.27 1.27)
				)
				(justify mirror)
			)
		)
		(property "Value" "SC2D2U25V5KX-2-GP"
			(at 0.0762 -6.1214 180)
			(unlocked yes)
			(layer "B.Fab")
			(hide yes)
			(effects
				(font
					(size 1.016 1.016)
					(thickness 0.1524)
				)
				(justify mirror)
			)
		)
		(property "Device Type" "C805H54"
			(at 0.0762 -8.1534 180)
			(unlocked yes)
			(layer "B.Fab")
			(hide yes)
			(effects
				(font
					(size 1.016 1.016)
					(thickness 0.1524)
				)
				(justify mirror)
			)
		)
		(duplicate_pad_numbers_are_jumpers no)
		(fp_line
			(start -0.635 0)
			(end 0.635 0)
			(stroke
				(width 0.508)
				(type default)
			)
			(layer "B.SilkS")
		)
		(fp_rect
			(start 0.9652 1.778)
			(end -0.9652 -1.778)
			(stroke
				(width 0)
				(type default)
			)
			(fill no)
			(layer "B.CrtYd")
		)
		(fp_poly
			(pts
				(xy 0.9652 -1.778) (xy -0.9652 -1.778) (xy -0.9652 1.778) (xy 0.9652 1.778)
			)
			(stroke
				(width 0)
				(type default)
			)
			(fill no)
			(layer "B.Fab")
		)
		(pad "1" smd rect
			(at 0 -0.9652)
			(size 1.397 1.143)
			(layers "B.Cu" "B.Mask" "B.Paste")
			(net "P12V_IOM_PGOOD")
		)
		(pad "2" smd rect
			(at 0 0.9652)
			(size 1.397 1.143)
			(layers "B.Cu" "B.Mask" "B.Paste")
			(net "GND")
		)
	)
	(footprint ""
		(layer "B.Cu")
		(at 176.0728 -71.0057)
		(property "Reference" "TP100"
			(at 0 0 0)
			(layer "B.SilkS")
			(hide yes)
			(effects
				(font
					(size 1.27 1.27)
				)
				(justify mirror)
			)
		)
		(property "Value" "TPAD28-2-GP"
			(at 0.0127 -1.6637 0)
			(unlocked yes)
			(layer "B.Fab")
			(hide yes)
			(effects
				(font
					(size 1.016 1.016)
					(thickness 0.1524)
				)
				(justify mirror)
			)
		)
		(property "Device Type" "TPAD28"
			(at 0.0127 -3.1877 0)
			(unlocked yes)
			(layer "B.Fab")
			(hide yes)
			(effects
				(font
					(size 1.016 1.016)
					(thickness 0.1524)
				)
				(justify mirror)
			)
		)
		(duplicate_pad_numbers_are_jumpers no)
		(fp_poly
			(pts
				(arc
					(start 0.3556 0)
					(mid -0.3556 0)
					(end 0.3556 0)
				)
			)
			(stroke
				(width 0)
				(type default)
			)
			(fill no)
			(layer "B.CrtYd")
		)
		(fp_poly
			(pts
				(arc
					(start 0.6096 0)
					(mid -0.6096 0)
					(end 0.6096 0)
				)
			)
			(stroke
				(width 0)
				(type default)
			)
			(fill no)
			(layer "B.Fab")
		)
		(pad "1" smd circle
			(at 0 0 180)
			(size 0.7112 0.7112)
			(layers "B.Cu" "B.Mask" "B.Paste")
			(net "IOC_GPIO_15")
		)
	)
	(footprint ""
		(layer "B.Cu")
		(at 11.345672 -144.098264 -90)
		(property "Reference" "C65"
			(at 0 0 90)
			(layer "B.SilkS")
			(hide yes)
			(effects
				(font
					(size 1.27 1.27)
				)
				(justify mirror)
			)
		)
		(property "Value" "SC1U16V3KX-5GP"
			(at 0 -2.8194 270)
			(unlocked yes)
			(layer "B.Fab")
			(hide yes)
			(effects
				(font
					(size 1.016 1.016)
					(thickness 0.1524)
				)
				(justify mirror)
			)
		)
		(property "Device Type" "C603H36"
			(at 0 -4.3434 270)
			(unlocked yes)
			(layer "B.Fab")
			(hide yes)
			(effects
				(font
					(size 1.016 1.016)
					(thickness 0.1524)
				)
				(justify mirror)
			)
		)
		(duplicate_pad_numbers_are_jumpers no)
		(fp_line
			(start -0.508 0)
			(end 0.508 0)
			(stroke
				(width 0.2032)
				(type default)
			)
			(layer "B.SilkS")
		)
		(fp_rect
			(start 0.5842 1.3335)
			(end -0.5842 -1.3335)
			(stroke
				(width 0)
				(type default)
			)
			(fill no)
			(layer "B.CrtYd")
		)
		(fp_rect
			(start 0.5842 1.3335)
			(end -0.5842 -1.3335)
			(stroke
				(width 0)
				(type default)
			)
			(fill no)
			(layer "B.Fab")
		)
		(pad "1" smd custom
			(at 0 -0.762 90)
			(size 0.2159 0.2159)
			(layers "B.Cu" "B.Mask" "B.Paste")
			(net "P2V5_STBY")
			(options
				(clearance outline)
				(anchor circle)
			)
			(primitives
				(gr_poly
					(pts
						(arc
							(start -0.3302 0.4318)
							(mid -0.402042 0.402042)
							(end -0.4318 0.3302)
						)
						(arc
							(start -0.4318 -0.3302)
							(mid -0.402042 -0.402042)
							(end -0.3302 -0.4318)
						)
						(arc
							(start 0.3302 -0.4318)
							(mid 0.402042 -0.402042)
							(end 0.4318 -0.3302)
						)
						(arc
							(start 0.4318 0.3302)
							(mid 0.402042 0.402042)
							(end 0.3302 0.4318)
						)
					)
					(width 0)
					(fill yes)
				)
			)
		)
		(pad "2" smd custom
			(at 0 0.762 90)
			(size 0.2159 0.2159)
			(layers "B.Cu" "B.Mask" "B.Paste")
			(net "GND")
			(options
				(clearance outline)
				(anchor circle)
			)
			(primitives
				(gr_poly
					(pts
						(arc
							(start -0.3302 0.4318)
							(mid -0.402042 0.402042)
							(end -0.4318 0.3302)
						)
						(arc
							(start -0.4318 -0.3302)
							(mid -0.402042 -0.402042)
							(end -0.3302 -0.4318)
						)
						(arc
							(start 0.3302 -0.4318)
							(mid 0.402042 -0.402042)
							(end 0.4318 -0.3302)
						)
						(arc
							(start 0.4318 0.3302)
							(mid 0.402042 0.402042)
							(end 0.3302 0.4318)
						)
					)
					(width 0)
					(fill yes)
				)
			)
		)
	)
)
